(kicad_pcb
	(version 20260206)
	(generator "pcbnew")
	(generator_version "10.0")
	(general
		(thickness 1.6)
		(legacy_teardrops no)
	)
	(paper "A4")
	(title_block
		(title "Wiwynn_Tioga_Pass_MB.brd")
		(comment 1 "Tioga Pass / footprints 4658-4663 of 4770")
	)
	(layers
		(0 "F.Cu" signal "TOP")
		(4 "In1.Cu" signal "L2GND")
		(6 "In2.Cu" signal "L3")
		(8 "In3.Cu" signal "L4GND")
		(10 "In4.Cu" signal "L5")
		(12 "In5.Cu" signal "L6GND")
		(14 "In6.Cu" signal "L7VCC")
		(16 "In7.Cu" signal "L8VCC")
		(18 "In8.Cu" signal "L9GND")
		(20 "In9.Cu" signal "L10")
		(22 "In10.Cu" signal "L11GND")
		(24 "In11.Cu" signal "L12")
		(26 "In12.Cu" signal "L13GND")
		(2 "B.Cu" signal "BOTTOM")
		(9 "F.Adhes" user "F.Adhesive")
		(11 "B.Adhes" user "B.Adhesive")
		(13 "F.Paste" user "Package Geometry/Pastemask Top")
		(15 "B.Paste" user "Package Geometry/Pastemask Bottom")
		(5 "F.SilkS" user "Ref Des/Silkscreen Top")
		(7 "B.SilkS" user "Ref Des/Silkscreen Bottom")
		(1 "F.Mask" user "Board Geometry/Soldermask Top")
		(3 "B.Mask" user "Board Geometry/Soldermask Bottom")
		(17 "Dwgs.User" user "User.Drawings")
		(19 "Cmts.User" user "User.Comments")
		(21 "Eco1.User" user "User.Eco1")
		(23 "Eco2.User" user "User.Eco2")
		(25 "Edge.Cuts" user "Board Geometry/Outline")
		(27 "Margin" user)
		(31 "F.CrtYd" user "Package Geometry/Place Bound Top")
		(29 "B.CrtYd" user "Package Geometry/Place Bound Bottom")
		(35 "F.Fab" user "Ref Des/Assembly Top")
		(33 "B.Fab" user "Ref Des/Assembly Bottom")
	)
	(footprint ""
		(layer "B.Cu")
		(at 367.827814 -125.507242 -90)
		(property "Reference" "R782"
			(at 0.8382 -0.67818 270)
			(unlocked yes)
			(layer "B.SilkS")
			(effects
				(font
					(size 0.4064 0.254)
					(thickness 0.1524)
				)
				(justify left mirror)
			)
		)
		(property "Value" ""
			(at 0 0 90)
			(layer "B.Fab")
			(effects
				(font
					(size 1.27 1.27)
				)
				(justify mirror)
			)
		)
		(duplicate_pad_numbers_are_jumpers no)
		(fp_poly
			(pts
				(xy 0.2794 -0.1016) (xy -0.2794 -0.1016) (xy -0.2794 0.9906) (xy 0.2794 0.9906)
			)
			(stroke
				(width 0)
				(type default)
			)
			(fill no)
			(layer "B.CrtYd")
		)
		(fp_line
			(start -0.2794 0.9906)
			(end -0.2794 -0.1016)
			(stroke
				(width 0.1)
				(type default)
			)
			(layer "B.Fab")
		)
		(fp_line
			(start 0.2794 0.9906)
			(end -0.2794 0.9906)
			(stroke
				(width 0.1)
				(type default)
			)
			(layer "B.Fab")
		)
		(fp_line
			(start -0.2794 -0.1016)
			(end 0.2794 -0.1016)
			(stroke
				(width 0.1)
				(type default)
			)
			(layer "B.Fab")
		)
		(fp_line
			(start 0.2794 -0.1016)
			(end 0.2794 0.9906)
			(stroke
				(width 0.1)
				(type default)
			)
			(layer "B.Fab")
		)
		(pad "1" smd rect
			(at 0 0 90)
			(size 0.508 0.508)
			(layers "B.Cu" "B.Mask" "B.Paste")
			(net "P3E_CPU0_PE1_PCH_RXN<9>")
		)
		(pad "2" smd rect
			(at 0 0.889 90)
			(size 0.508 0.508)
			(layers "B.Cu" "B.Mask" "B.Paste")
			(net "P3E_CPU0_PE1_PCH_CON_RXN<9>")
		)
		(zone
			(layer "B.Cu")
			(hatch none 0.5)
			(connect_pads
				(clearance 0)
			)
			(min_thickness 0.25)
			(keepout
				(tracks not_allowed)
				(vias allowed)
				(pads allowed)
				(copperpour not_allowed)
				(footprints allowed)
			)
			(placement
				(enabled no)
				(sheetname "")
			)
			(fill
				(thermal_gap 0.5)
				(thermal_bridge_width 0.5)
				(island_removal_mode 0)
			)
			(polygon
				(pts
					(xy 367.192814 -125.253242) (xy 367.192814 -125.761242) (xy 367.573814 -125.761242) (xy 367.573814 -125.253242)
				)
			)
		)
		(zone
			(layer "B.Cu")
			(hatch none 0.5)
			(connect_pads
				(clearance 0)
			)
			(min_thickness 0.25)
			(keepout
				(tracks allowed)
				(vias not_allowed)
				(pads allowed)
				(copperpour not_allowed)
				(footprints allowed)
			)
			(placement
				(enabled no)
				(sheetname "")
			)
			(fill
				(thermal_gap 0.5)
				(thermal_bridge_width 0.5)
				(island_removal_mode 0)
			)
			(polygon
				(pts
					(xy 367.573814 -125.253242) (xy 367.573814 -125.761242) (xy 367.192814 -125.761242) (xy 367.192814 -125.253242)
				)
			)
		)
	)
	(footprint ""
		(layer "B.Cu")
		(at 279.046686 -79.60614 180)
		(property "Reference" "C4P2"
			(at 0 0 0)
			(layer "B.SilkS")
			(hide yes)
			(effects
				(font
					(size 1.27 1.27)
				)
				(justify mirror)
			)
		)
		(property "Value" ""
			(at 0 0 0)
			(layer "B.Fab")
			(effects
				(font
					(size 1.27 1.27)
				)
				(justify mirror)
			)
		)
		(duplicate_pad_numbers_are_jumpers no)
		(fp_poly
			(pts
				(xy 0.7239 -0.2159) (xy -0.7239 -0.2159) (xy -0.7239 1.9939) (xy 0.7239 1.9939)
			)
			(stroke
				(width 0)
				(type default)
			)
			(fill no)
			(layer "B.CrtYd")
		)
		(fp_line
			(start 0.7239 1.9939)
			(end -0.7239 1.9939)
			(stroke
				(width 0.1)
				(type default)
			)
			(layer "B.Fab")
		)
		(fp_line
			(start 0.7239 -0.2159)
			(end 0.7239 1.9939)
			(stroke
				(width 0.1)
				(type default)
			)
			(layer "B.Fab")
		)
		(fp_line
			(start -0.7239 1.9939)
			(end -0.7239 -0.2159)
			(stroke
				(width 0.1)
				(type default)
			)
			(layer "B.Fab")
		)
		(fp_line
			(start -0.7239 -0.2159)
			(end 0.7239 -0.2159)
			(stroke
				(width 0.1)
				(type default)
			)
			(layer "B.Fab")
		)
		(pad "1" smd rect
			(at 0 0)
			(size 1.27 1.016)
			(layers "B.Cu" "B.Mask" "B.Paste")
			(net "PVCCMCP_CPU0")
		)
		(pad "2" smd rect
			(at 0 1.778)
			(size 1.27 1.016)
			(layers "B.Cu" "B.Mask" "B.Paste")
			(net "GND")
		)
		(zone
			(layer "B.Cu")
			(hatch none 0.5)
			(connect_pads
				(clearance 0)
			)
			(min_thickness 0.25)
			(keepout
				(tracks not_allowed)
				(vias allowed)
				(pads allowed)
				(copperpour not_allowed)
				(footprints allowed)
			)
			(placement
				(enabled no)
				(sheetname "")
			)
			(fill
				(thermal_gap 0.5)
				(thermal_bridge_width 0.5)
				(island_removal_mode 0)
			)
			(polygon
				(pts
					(xy 278.411686 -80.11414) (xy 279.681686 -80.11414) (xy 279.681686 -80.87614) (xy 278.411686 -80.87614)
				)
			)
		)
	)
	(footprint ""
		(layer "B.Cu")
		(at 80.757268 -145.0086 -90)
		(property "Reference" "C8L10"
			(at -1.848866 0.752348 270)
			(unlocked yes)
			(layer "B.SilkS")
			(effects
				(font
					(size 1.27 0.9652)
					(thickness 0.1524)
				)
				(justify mirror)
			)
		)
		(property "Value" ""
			(at 0 0 90)
			(layer "B.Fab")
			(effects
				(font
					(size 1.27 1.27)
				)
				(justify mirror)
			)
		)
		(duplicate_pad_numbers_are_jumpers no)
		(fp_rect
			(start 0.500126 1.598422)
			(end -0.500126 -0.201422)
			(stroke
				(width 0)
				(type default)
			)
			(fill no)
			(layer "B.CrtYd")
		)
		(fp_line
			(start -0.500126 1.598422)
			(end 0.500126 1.598422)
			(stroke
				(width 0.1)
				(type default)
			)
			(layer "B.Fab")
		)
		(fp_line
			(start 0.500126 1.598422)
			(end 0.500126 -0.201422)
			(stroke
				(width 0.1)
				(type default)
			)
			(layer "B.Fab")
		)
		(fp_line
			(start -0.500126 -0.201422)
			(end -0.500126 1.598422)
			(stroke
				(width 0.1)
				(type default)
			)
			(layer "B.Fab")
		)
		(fp_line
			(start 0.500126 -0.201422)
			(end -0.500126 -0.201422)
			(stroke
				(width 0.1)
				(type default)
			)
			(layer "B.Fab")
		)
		(pad "1" smd rect
			(at 0 0 180)
			(size 0.889 0.9906)
			(layers "B.Cu" "B.Mask" "B.Paste")
			(net "PVDDQ_KLM")
		)
		(pad "2" smd rect
			(at 0 1.397 180)
			(size 0.889 0.9906)
			(layers "B.Cu" "B.Mask" "B.Paste")
			(net "GND")
		)
		(zone
			(layer "B.Cu")
			(hatch none 0.5)
			(connect_pads
				(clearance 0)
			)
			(min_thickness 0.25)
			(keepout
				(tracks not_allowed)
				(vias allowed)
				(pads allowed)
				(copperpour not_allowed)
				(footprints allowed)
			)
			(placement
				(enabled no)
				(sheetname "")
			)
			(fill
				(thermal_gap 0.5)
				(thermal_bridge_width 0.5)
				(island_removal_mode 0)
			)
			(polygon
				(pts
					(xy 79.804768 -144.5133) (xy 80.312768 -144.5133) (xy 80.312768 -145.5039) (xy 79.804768 -145.5039)
				)
			)
		)
		(zone
			(layer "B.Cu")
			(hatch none 0.5)
			(connect_pads
				(clearance 0)
			)
			(min_thickness 0.25)
			(keepout
				(tracks allowed)
				(vias not_allowed)
				(pads allowed)
				(copperpour not_allowed)
				(footprints allowed)
			)
			(placement
				(enabled no)
				(sheetname "")
			)
			(fill
				(thermal_gap 0.5)
				(thermal_bridge_width 0.5)
				(island_removal_mode 0)
			)
			(polygon
				(pts
					(xy 79.804768 -144.5133) (xy 80.312768 -144.5133) (xy 80.312768 -145.5039) (xy 79.804768 -145.5039)
				)
			)
		)
	)
	(footprint ""
		(layer "B.Cu")
		(at 476.479616 -140.712952 90)
		(property "Reference" "U6W1"
			(at 0 0 90)
			(layer "B.SilkS")
			(hide yes)
			(effects
				(font
					(size 1.27 1.27)
				)
				(justify mirror)
			)
		)
		(property "Value" "*"
			(at 0 -7.0485 90)
			(unlocked yes)
			(layer "B.Fab")
			(hide yes)
			(effects
				(font
					(size 1.27 1.016)
					(thickness 0.1524)
				)
				(justify mirror)
			)
		)
		(property "Device Type" "TCA9555PWR-GP_DISCRET-GC1-TCA9A"
			(at 0 -8.6995 90)
			(unlocked yes)
			(layer "B.Fab")
			(hide yes)
			(effects
				(font
					(size 1.27 1.016)
					(thickness 0.1524)
				)
				(justify mirror)
			)
		)
		(duplicate_pad_numbers_are_jumpers no)
		(fp_line
			(start 4.2291 -1.397)
			(end -3.81 -1.397)
			(stroke
				(width 0.1524)
				(type default)
			)
			(layer "B.SilkS")
		)
		(fp_line
			(start -3.81 -1.397)
			(end -3.81 1.397)
			(stroke
				(width 0.1524)
				(type default)
			)
			(layer "B.SilkS")
		)
		(fp_line
			(start 4.2291 -0.8001)
			(end 3.429 0)
			(stroke
				(width 0.1524)
				(type default)
			)
			(layer "B.SilkS")
		)
		(fp_line
			(start 3.429 0)
			(end 4.2291 0.8001)
			(stroke
				(width 0.1524)
				(type default)
			)
			(layer "B.SilkS")
		)
		(fp_line
			(start -3.81 1.397)
			(end 4.2291 1.397)
			(stroke
				(width 0.1524)
				(type default)
			)
			(layer "B.SilkS")
		)
		(fp_line
			(start 4.22656 3.81)
			(end 4.2291 1.397)
			(stroke
				(width 0.508)
				(type default)
			)
			(layer "B.SilkS")
		)
		(fp_line
			(start 4.2291 3.937)
			(end 4.2291 -1.397)
			(stroke
				(width 0.1524)
				(type default)
			)
			(layer "B.SilkS")
		)
		(fp_poly
			(pts
				(xy 3.90652 -1.8542) (xy -3.90652 -1.8542) (xy -3.90652 1.8542) (xy 3.90652 1.8542)
			)
			(stroke
				(width 0)
				(type default)
			)
			(fill yes)
			(layer "B.SilkS")
		)
		(fp_poly
			(pts
				(xy 4.2164 3.81) (xy -4.2164 3.81) (xy -4.22656 -3.81) (xy 4.2164 -3.81)
			)
			(stroke
				(width 0)
				(type default)
			)
			(fill no)
			(layer "B.CrtYd")
		)
		(fp_poly
			(pts
				(xy 4.22656 -3.81) (xy -4.22656 -3.81) (xy -4.22656 3.81) (xy 4.22656 3.81)
			)
			(stroke
				(width 0)
				(type default)
			)
			(fill no)
			(layer "B.Fab")
		)
		(pad "1" smd rect
			(at 3.57632 2.8194 270)
			(size 0.3556 1.524)
			(layers "B.Cu" "B.Mask" "B.Paste")
			(net "PCA9555_INT_N")
		)
		(pad "2" smd rect
			(at 2.92608 2.8194 270)
			(size 0.3556 1.524)
			(layers "B.Cu" "B.Mask" "B.Paste")
			(net "PCA9555_A1")
		)
		(pad "3" smd rect
			(at 2.27584 2.8194 270)
			(size 0.3556 1.524)
			(layers "B.Cu" "B.Mask" "B.Paste")
			(net "PCA9555_A2")
		)
		(pad "4" smd rect
			(at 1.6256 2.8194 270)
			(size 0.3556 1.524)
			(layers "B.Cu" "B.Mask" "B.Paste")
			(net "LED_POSTCODE_0_R")
		)
		(pad "5" smd rect
			(at 0.97536 2.8194 270)
			(size 0.3556 1.524)
			(layers "B.Cu" "B.Mask" "B.Paste")
			(net "LED_POSTCODE_1_R")
		)
		(pad "6" smd rect
			(at 0.32512 2.8194 270)
			(size 0.3556 1.524)
			(layers "B.Cu" "B.Mask" "B.Paste")
			(net "LED_POSTCODE_2_R")
		)
		(pad "7" smd rect
			(at -0.32512 2.8194 270)
			(size 0.3556 1.524)
			(layers "B.Cu" "B.Mask" "B.Paste")
			(net "LED_POSTCODE_3_R")
		)
		(pad "8" smd rect
			(at -0.97536 2.8194 270)
			(size 0.3556 1.524)
			(layers "B.Cu" "B.Mask" "B.Paste")
			(net "LED_POSTCODE_4_R")
		)
		(pad "9" smd rect
			(at -1.6256 2.8194 270)
			(size 0.3556 1.524)
			(layers "B.Cu" "B.Mask" "B.Paste")
			(net "LED_POSTCODE_5_R")
		)
		(pad "10" smd rect
			(at -2.27584 2.8194 270)
			(size 0.3556 1.524)
			(layers "B.Cu" "B.Mask" "B.Paste")
			(net "LED_POSTCODE_6_R")
		)
		(pad "11" smd rect
			(at -2.92608 2.8194 270)
			(size 0.3556 1.524)
			(layers "B.Cu" "B.Mask" "B.Paste")
			(net "LED_POSTCODE_7_R")
		)
		(pad "12" smd rect
			(at -3.57632 2.8194 270)
			(size 0.3556 1.524)
			(layers "B.Cu" "B.Mask" "B.Paste")
			(net "GND")
		)
		(pad "13" smd rect
			(at -3.57632 -2.8194 270)
			(size 0.3556 1.524)
			(layers "B.Cu" "B.Mask" "B.Paste")
			(net "FM_DEBUG_RST_BTN_N")
		)
		(pad "14" smd rect
			(at -2.92608 -2.8194 270)
			(size 0.3556 1.524)
			(layers "B.Cu" "B.Mask" "B.Paste")
			(net "FP_PWR_BTN_R_N")
		)
		(pad "15" smd rect
			(at -2.27584 -2.8194 270)
			(size 0.3556 1.524)
			(layers "B.Cu" "B.Mask" "B.Paste")
			(net "PWRGD_SYS_PWROK")
		)
		(pad "16" smd rect
			(at -1.6256 -2.8194 270)
			(size 0.3556 1.524)
			(layers "B.Cu" "B.Mask" "B.Paste")
			(net "RST_PLTRST_N")
		)
		(pad "17" smd rect
			(at -0.97536 -2.8194 270)
			(size 0.3556 1.524)
			(layers "B.Cu" "B.Mask" "B.Paste")
			(net "PWRGD_DSW_PWROK")
		)
		(pad "18" smd rect
			(at -0.32512 -2.8194 270)
			(size 0.3556 1.524)
			(layers "B.Cu" "B.Mask" "B.Paste")
			(net "FM_CPU_CATERR_MSMI_LVT3_N")
		)
		(pad "19" smd rect
			(at 0.32512 -2.8194 270)
			(size 0.3556 1.524)
			(layers "B.Cu" "B.Mask" "B.Paste")
			(net "FM_SLPS3_N")
		)
		(pad "20" smd rect
			(at 0.97536 -2.8194 270)
			(size 0.3556 1.524)
			(layers "B.Cu" "B.Mask" "B.Paste")
			(net "FM_UART_SWITCH_N")
		)
		(pad "21" smd rect
			(at 1.6256 -2.8194 270)
			(size 0.3556 1.524)
			(layers "B.Cu" "B.Mask" "B.Paste")
			(net "PCA9555_A0")
		)
		(pad "22" smd rect
			(at 2.27584 -2.8194 270)
			(size 0.3556 1.524)
			(layers "B.Cu" "B.Mask" "B.Paste")
			(net "SMB_DEBUG_STBY_LVC3_SCL")
		)
		(pad "23" smd rect
			(at 2.92608 -2.8194 270)
			(size 0.3556 1.524)
			(layers "B.Cu" "B.Mask" "B.Paste")
			(net "SMB_DEBUG_STBY_LVC3_SDA")
		)
		(pad "24" smd rect
			(at 3.57632 -2.8194 270)
			(size 0.3556 1.524)
			(layers "B.Cu" "B.Mask" "B.Paste")
			(net "P3V3_STBY")
		)
	)
	(footprint ""
		(layer "B.Cu")
		(at 5.62356 -6.237986 90)
		(property "Reference" "C1G4"
			(at 0 0 90)
			(layer "B.SilkS")
			(hide yes)
			(effects
				(font
					(size 1.27 1.27)
				)
				(justify mirror)
			)
		)
		(property "Value" "*"
			(at -1.1811 -2.8194 90)
			(unlocked yes)
			(layer "B.Fab")
			(hide yes)
			(effects
				(font
					(size 1.27 1.016)
					(thickness 0.1524)
				)
				(justify mirror)
			)
		)
		(property "Device Type" "SC1U10V2KX-4-GP_SMD-BCG6-SC1U1A"
			(at -1.1811 -4.3434 90)
			(unlocked yes)
			(layer "B.Fab")
			(hide yes)
			(effects
				(font
					(size 1.27 1.016)
					(thickness 0.1524)
				)
				(justify mirror)
			)
		)
		(duplicate_pad_numbers_are_jumpers no)
		(fp_rect
			(start 0.4318 0.9525)
			(end -0.4318 -0.9525)
			(stroke
				(width 0)
				(type default)
			)
			(fill no)
			(layer "B.CrtYd")
		)
		(fp_rect
			(start 0.4318 0.9525)
			(end -0.4318 -0.9525)
			(stroke
				(width 0)
				(type default)
			)
			(fill no)
			(layer "B.Fab")
		)
		(pad "1" smd custom
			(at 0 -0.4445 270)
			(size 0.1524 0.1524)
			(layers "B.Cu" "B.Mask" "B.Paste")
			(net "P5V_STBY")
			(options
				(clearance outline)
				(anchor circle)
			)
			(primitives
				(gr_poly
					(pts
						(arc
							(start 0.3048 0.2032)
							(mid 0.275042 0.275042)
							(end 0.2032 0.3048)
						)
						(arc
							(start -0.2032 0.3048)
							(mid -0.275042 0.275042)
							(end -0.3048 0.2032)
						)
						(arc
							(start -0.3048 -0.2032)
							(mid -0.275042 -0.275042)
							(end -0.2032 -0.3048)
						)
						(arc
							(start 0.2032 -0.3048)
							(mid 0.275042 -0.275042)
							(end 0.3048 -0.2032)
						)
					)
					(width 0)
					(fill yes)
				)
			)
		)
		(pad "2" smd custom
			(at 0 0.4445 270)
			(size 0.1524 0.1524)
			(layers "B.Cu" "B.Mask" "B.Paste")
			(net "GND")
			(options
				(clearance outline)
				(anchor circle)
			)
			(primitives
				(gr_poly
					(pts
						(arc
							(start 0.3048 0.2032)
							(mid 0.275042 0.275042)
							(end 0.2032 0.3048)
						)
						(arc
							(start -0.2032 0.3048)
							(mid -0.275042 0.275042)
							(end -0.3048 0.2032)
						)
						(arc
							(start -0.3048 -0.2032)
							(mid -0.275042 -0.275042)
							(end -0.2032 -0.3048)
						)
						(arc
							(start 0.2032 -0.3048)
							(mid 0.275042 -0.275042)
							(end 0.3048 -0.2032)
						)
					)
					(width 0)
					(fill yes)
				)
			)
		)
	)
	(footprint ""
		(layer "B.Cu")
		(at 376.8598 -131.6228 180)
		(property "Reference" "C3M30"
			(at 0 0 0)
			(layer "B.SilkS")
			(hide yes)
			(effects
				(font
					(size 1.27 1.27)
				)
				(justify mirror)
			)
		)
		(property "Value" ""
			(at 0 0 0)
			(layer "B.Fab")
			(effects
				(font
					(size 1.27 1.27)
				)
				(justify mirror)
			)
		)
		(duplicate_pad_numbers_are_jumpers no)
		(fp_poly
			(pts
				(xy -0.3048 -0.1016) (xy -0.3048 0.9906) (xy 0.3048 0.9906) (xy 0.3048 -0.1016)
			)
			(stroke
				(width 0)
				(type default)
			)
			(fill no)
			(layer "B.CrtYd")
		)
		(fp_line
			(start 0.3048 0.9906)
			(end -0.3048 0.9906)
			(stroke
				(width 0.1)
				(type default)
			)
			(layer "B.Fab")
		)
		(fp_line
			(start 0.3048 -0.1016)
			(end 0.3048 0.9906)
			(stroke
				(width 0.1)
				(type default)
			)
			(layer "B.Fab")
		)
		(fp_line
			(start -0.3048 0.9906)
			(end -0.3048 -0.1016)
			(stroke
				(width 0.1)
				(type default)
			)
			(layer "B.Fab")
		)
		(fp_line
			(start -0.3048 -0.1016)
			(end 0.3048 -0.1016)
			(stroke
				(width 0.1)
				(type default)
			)
			(layer "B.Fab")
		)
		(pad "1" smd rect
			(at 0 0)
			(size 0.508 0.508)
			(layers "B.Cu" "B.Mask" "B.Paste")
			(net "P1V05_PCH_STBY")
		)
		(pad "2" smd rect
			(at 0 0.889)
			(size 0.508 0.508)
			(layers "B.Cu" "B.Mask" "B.Paste")
			(net "GND")
		)
		(zone
			(layer "B.Cu")
			(hatch none 0.5)
			(connect_pads
				(clearance 0)
			)
			(min_thickness 0.25)
			(keepout
				(tracks not_allowed)
				(vias allowed)
				(pads allowed)
				(copperpour not_allowed)
				(footprints allowed)
			)
			(placement
				(enabled no)
				(sheetname "")
			)
			(fill
				(thermal_gap 0.5)
				(thermal_bridge_width 0.5)
				(island_removal_mode 0)
			)
			(polygon
				(pts
					(xy 376.6058 -132.2578) (xy 377.1138 -132.2578) (xy 377.1138 -131.8768) (xy 376.6058 -131.8768)
				)
			)
		)
		(zone
			(layer "B.Cu")
			(hatch none 0.5)
			(connect_pads
				(clearance 0)
			)
			(min_thickness 0.25)
			(keepout
				(tracks allowed)
				(vias not_allowed)
				(pads allowed)
				(copperpour not_allowed)
				(footprints allowed)
			)
			(placement
				(enabled no)
				(sheetname "")
			)
			(fill
				(thermal_gap 0.5)
				(thermal_bridge_width 0.5)
				(island_removal_mode 0)
			)
			(polygon
				(pts
					(xy 376.6058 -131.8768) (xy 377.1138 -131.8768) (xy 377.1138 -132.2578) (xy 376.6058 -132.2578)
				)
			)
		)
	)
)
